(kicad_pcb
	(version 20260206)
	(generator "pcbnew")
	(generator_version "10.0")
	(general
		(thickness 1.6)
		(legacy_teardrops no)
	)
	(paper "A4")
	(title_block
		(title "01162023_DA0F0TEBIF0_F0T_Expander_BD_F_brd_V02_OCP.brd")
		(comment 1 "Grand Teton / footprints 5220-5225 of 9728")
	)
	(layers
		(0 "F.Cu" signal "TOP")
		(4 "In1.Cu" signal "GND")
		(6 "In2.Cu" signal "VCC")
		(8 "In3.Cu" signal "VCC1")
		(10 "In4.Cu" signal "GND1")
		(12 "In5.Cu" signal "IN1")
		(14 "In6.Cu" signal "GND2")
		(16 "In7.Cu" signal "IN2")
		(18 "In8.Cu" signal "GND3")
		(20 "In9.Cu" signal "IN3")
		(22 "In10.Cu" signal "GND4")
		(24 "In11.Cu" signal "IN4")
		(26 "In12.Cu" signal "GND5")
		(28 "In13.Cu" signal "IN5")
		(30 "In14.Cu" signal "GND6")
		(32 "In15.Cu" signal "IN6")
		(34 "In16.Cu" signal "GND7")
		(2 "B.Cu" signal "BOTTOM")
		(9 "F.Adhes" user "F.Adhesive")
		(11 "B.Adhes" user "B.Adhesive")
		(13 "F.Paste" user "Package Geometry/Pastemask Top")
		(15 "B.Paste" user "Package Geometry/Pastemask Bottom")
		(5 "F.SilkS" user "Ref Des/Silkscreen Top")
		(7 "B.SilkS" user "Ref Des/Silkscreen Bottom")
		(1 "F.Mask" user "Board Geometry/Soldermask Top")
		(3 "B.Mask" user "Board Geometry/Soldermask Bottom")
		(17 "Dwgs.User" user "User.Drawings")
		(19 "Cmts.User" user "User.Comments")
		(21 "Eco1.User" user "User.Eco1")
		(23 "Eco2.User" user "User.Eco2")
		(25 "Edge.Cuts" user "Board Geometry/Outline")
		(27 "Margin" user)
		(31 "F.CrtYd" user "Package Geometry/Place Bound Top")
		(29 "B.CrtYd" user "Package Geometry/Place Bound Bottom")
		(35 "F.Fab" user "Ref Des/Assembly Top")
		(33 "B.Fab" user "Ref Des/Assembly Bottom")
	)
	(footprint ""
		(layer "F.Cu")
		(at 194.367912 -56.353456)
		(property "Reference" "C2866"
			(at 0 0 0)
			(layer "F.SilkS")
			(hide yes)
			(effects
				(font
					(size 1.27 1.27)
				)
			)
		)
		(property "Value" ""
			(at 0 0 0)
			(layer "F.Fab")
			(effects
				(font
					(size 1.27 1.27)
				)
			)
		)
		(duplicate_pad_numbers_are_jumpers no)
		(fp_line
			(start -0.7874 -0.4064)
			(end 0.7874 -0.4064)
			(stroke
				(width 0.1524)
				(type default)
			)
			(layer "F.SilkS")
		)
		(fp_line
			(start -0.7874 0.4064)
			(end -0.7874 -0.4064)
			(stroke
				(width 0.1524)
				(type default)
			)
			(layer "F.SilkS")
		)
		(fp_line
			(start 0.7874 -0.4064)
			(end 0.7874 0.4064)
			(stroke
				(width 0.1524)
				(type default)
			)
			(layer "F.SilkS")
		)
		(fp_line
			(start 0.7874 0.4064)
			(end -0.7874 0.4064)
			(stroke
				(width 0.1524)
				(type default)
			)
			(layer "F.SilkS")
		)
		(fp_line
			(start -0.67945 -0.305054)
			(end -0.12065 -0.305054)
			(stroke
				(width 0.1)
				(type default)
			)
			(layer "F.Fab")
		)
		(fp_line
			(start -0.67945 0.3048)
			(end -0.67945 -0.305054)
			(stroke
				(width 0.1)
				(type default)
			)
			(layer "F.Fab")
		)
		(fp_line
			(start -0.12065 -0.305054)
			(end -0.12065 -0.2794)
			(stroke
				(width 0.1)
				(type default)
			)
			(layer "F.Fab")
		)
		(fp_line
			(start -0.12065 -0.2794)
			(end 0.12065 -0.2794)
			(stroke
				(width 0.1)
				(type default)
			)
			(layer "F.Fab")
		)
		(fp_line
			(start -0.12065 0.2794)
			(end -0.12065 0.3048)
			(stroke
				(width 0.1)
				(type default)
			)
			(layer "F.Fab")
		)
		(fp_line
			(start -0.12065 0.3048)
			(end -0.67945 0.3048)
			(stroke
				(width 0.1)
				(type default)
			)
			(layer "F.Fab")
		)
		(fp_line
			(start 0.120396 0.2794)
			(end -0.12065 0.2794)
			(stroke
				(width 0.1)
				(type default)
			)
			(layer "F.Fab")
		)
		(fp_line
			(start 0.120396 0.3048)
			(end 0.120396 0.2794)
			(stroke
				(width 0.1)
				(type default)
			)
			(layer "F.Fab")
		)
		(fp_line
			(start 0.12065 -0.3048)
			(end 0.67945 -0.3048)
			(stroke
				(width 0.1)
				(type default)
			)
			(layer "F.Fab")
		)
		(fp_line
			(start 0.12065 -0.2794)
			(end 0.12065 -0.3048)
			(stroke
				(width 0.1)
				(type default)
			)
			(layer "F.Fab")
		)
		(fp_line
			(start 0.67945 -0.3048)
			(end 0.67945 0.3048)
			(stroke
				(width 0.1)
				(type default)
			)
			(layer "F.Fab")
		)
		(fp_line
			(start 0.67945 0.3048)
			(end 0.120396 0.3048)
			(stroke
				(width 0.1)
				(type default)
			)
			(layer "F.Fab")
		)
		(pad "1" smd circle
			(at -0.40005 0)
			(size 0 0)
			(layers "F.Cu" "F.Mask" "F.Paste")
			(net "SSD6_PWR_EN_R")
		)
		(pad "2" smd circle
			(at 0.40005 0)
			(size 0 0)
			(layers "F.Cu" "F.Mask" "F.Paste")
			(net "GND")
		)
	)
	(footprint ""
		(layer "F.Cu")
		(at 349.426276 -37.929566 90)
		(property "Reference" "R5567"
			(at 0 0 90)
			(layer "F.SilkS")
			(hide yes)
			(effects
				(font
					(size 1.27 1.27)
				)
			)
		)
		(property "Value" ""
			(at 0 0 90)
			(layer "F.Fab")
			(effects
				(font
					(size 1.27 1.27)
				)
			)
		)
		(duplicate_pad_numbers_are_jumpers no)
		(fp_line
			(start 0.7874 -0.4064)
			(end 0.7874 0.4064)
			(stroke
				(width 0.1524)
				(type default)
			)
			(layer "F.SilkS")
		)
		(fp_line
			(start -0.7874 -0.4064)
			(end 0.7874 -0.4064)
			(stroke
				(width 0.1524)
				(type default)
			)
			(layer "F.SilkS")
		)
		(fp_line
			(start 0.7874 0.4064)
			(end -0.7874 0.4064)
			(stroke
				(width 0.1524)
				(type default)
			)
			(layer "F.SilkS")
		)
		(fp_line
			(start -0.7874 0.4064)
			(end -0.7874 -0.4064)
			(stroke
				(width 0.1524)
				(type default)
			)
			(layer "F.SilkS")
		)
		(fp_line
			(start -0.12065 -0.305054)
			(end -0.12065 -0.2794)
			(stroke
				(width 0.1)
				(type default)
			)
			(layer "F.Fab")
		)
		(fp_line
			(start -0.67945 -0.305054)
			(end -0.12065 -0.305054)
			(stroke
				(width 0.1)
				(type default)
			)
			(layer "F.Fab")
		)
		(fp_line
			(start 0.67945 -0.3048)
			(end 0.67945 0.3048)
			(stroke
				(width 0.1)
				(type default)
			)
			(layer "F.Fab")
		)
		(fp_line
			(start 0.12065 -0.3048)
			(end 0.67945 -0.3048)
			(stroke
				(width 0.1)
				(type default)
			)
			(layer "F.Fab")
		)
		(fp_line
			(start 0.12065 -0.2794)
			(end 0.12065 -0.3048)
			(stroke
				(width 0.1)
				(type default)
			)
			(layer "F.Fab")
		)
		(fp_line
			(start -0.12065 -0.2794)
			(end 0.12065 -0.2794)
			(stroke
				(width 0.1)
				(type default)
			)
			(layer "F.Fab")
		)
		(fp_line
			(start 0.120396 0.2794)
			(end -0.12065 0.2794)
			(stroke
				(width 0.1)
				(type default)
			)
			(layer "F.Fab")
		)
		(fp_line
			(start -0.12065 0.2794)
			(end -0.12065 0.3048)
			(stroke
				(width 0.1)
				(type default)
			)
			(layer "F.Fab")
		)
		(fp_line
			(start 0.67945 0.3048)
			(end 0.120396 0.3048)
			(stroke
				(width 0.1)
				(type default)
			)
			(layer "F.Fab")
		)
		(fp_line
			(start 0.120396 0.3048)
			(end 0.120396 0.2794)
			(stroke
				(width 0.1)
				(type default)
			)
			(layer "F.Fab")
		)
		(fp_line
			(start -0.12065 0.3048)
			(end -0.67945 0.3048)
			(stroke
				(width 0.1)
				(type default)
			)
			(layer "F.Fab")
		)
		(fp_line
			(start -0.67945 0.3048)
			(end -0.67945 -0.305054)
			(stroke
				(width 0.1)
				(type default)
			)
			(layer "F.Fab")
		)
		(pad "1" smd circle
			(at -0.40005 0 90)
			(size 0 0)
			(layers "F.Cu" "F.Mask" "F.Paste")
			(net "SSD12_AUX_P3V3_EN_R")
		)
		(pad "2" smd circle
			(at 0.40005 0 90)
			(size 0 0)
			(layers "F.Cu" "F.Mask" "F.Paste")
			(net "SSD12_AUX_P3V3_EN")
		)
	)
	(footprint ""
		(layer "F.Cu")
		(at 223.45396 -65.712086 90)
		(property "Reference" "R3762"
			(at 0 0 90)
			(layer "F.SilkS")
			(hide yes)
			(effects
				(font
					(size 1.27 1.27)
				)
			)
		)
		(property "Value" ""
			(at 0 0 90)
			(layer "F.Fab")
			(effects
				(font
					(size 1.27 1.27)
				)
			)
		)
		(duplicate_pad_numbers_are_jumpers no)
		(fp_line
			(start 0.7874 -0.4064)
			(end 0.7874 0.4064)
			(stroke
				(width 0.1524)
				(type default)
			)
			(layer "F.SilkS")
		)
		(fp_line
			(start -0.7874 -0.4064)
			(end 0.7874 -0.4064)
			(stroke
				(width 0.1524)
				(type default)
			)
			(layer "F.SilkS")
		)
		(fp_line
			(start 0.7874 0.4064)
			(end -0.7874 0.4064)
			(stroke
				(width 0.1524)
				(type default)
			)
			(layer "F.SilkS")
		)
		(fp_line
			(start -0.7874 0.4064)
			(end -0.7874 -0.4064)
			(stroke
				(width 0.1524)
				(type default)
			)
			(layer "F.SilkS")
		)
		(fp_line
			(start -0.12065 -0.305054)
			(end -0.12065 -0.2794)
			(stroke
				(width 0.1)
				(type default)
			)
			(layer "F.Fab")
		)
		(fp_line
			(start -0.67945 -0.305054)
			(end -0.12065 -0.305054)
			(stroke
				(width 0.1)
				(type default)
			)
			(layer "F.Fab")
		)
		(fp_line
			(start 0.67945 -0.3048)
			(end 0.67945 0.3048)
			(stroke
				(width 0.1)
				(type default)
			)
			(layer "F.Fab")
		)
		(fp_line
			(start 0.12065 -0.3048)
			(end 0.67945 -0.3048)
			(stroke
				(width 0.1)
				(type default)
			)
			(layer "F.Fab")
		)
		(fp_line
			(start 0.12065 -0.2794)
			(end 0.12065 -0.3048)
			(stroke
				(width 0.1)
				(type default)
			)
			(layer "F.Fab")
		)
		(fp_line
			(start -0.12065 -0.2794)
			(end 0.12065 -0.2794)
			(stroke
				(width 0.1)
				(type default)
			)
			(layer "F.Fab")
		)
		(fp_line
			(start 0.120396 0.2794)
			(end -0.12065 0.2794)
			(stroke
				(width 0.1)
				(type default)
			)
			(layer "F.Fab")
		)
		(fp_line
			(start -0.12065 0.2794)
			(end -0.12065 0.3048)
			(stroke
				(width 0.1)
				(type default)
			)
			(layer "F.Fab")
		)
		(fp_line
			(start 0.67945 0.3048)
			(end 0.120396 0.3048)
			(stroke
				(width 0.1)
				(type default)
			)
			(layer "F.Fab")
		)
		(fp_line
			(start 0.120396 0.3048)
			(end 0.120396 0.2794)
			(stroke
				(width 0.1)
				(type default)
			)
			(layer "F.Fab")
		)
		(fp_line
			(start -0.12065 0.3048)
			(end -0.67945 0.3048)
			(stroke
				(width 0.1)
				(type default)
			)
			(layer "F.Fab")
		)
		(fp_line
			(start -0.67945 0.3048)
			(end -0.67945 -0.305054)
			(stroke
				(width 0.1)
				(type default)
			)
			(layer "F.Fab")
		)
		(pad "1" smd circle
			(at -0.40005 0 90)
			(size 0 0)
			(layers "F.Cu" "F.Mask" "F.Paste")
			(net "SMB_FIO_R2_SDA")
		)
		(pad "2" smd circle
			(at 0.40005 0 90)
			(size 0 0)
			(layers "F.Cu" "F.Mask" "F.Paste")
			(net "SMB_FIO_R1_SDA")
		)
	)
	(footprint ""
		(layer "F.Cu")
		(at 331.131164 -350.098614 90)
		(property "Reference" "C531"
			(at 0 0 90)
			(layer "F.SilkS")
			(hide yes)
			(effects
				(font
					(size 1.27 1.27)
				)
			)
		)
		(property "Value" ""
			(at 0 0 90)
			(layer "F.Fab")
			(effects
				(font
					(size 1.27 1.27)
				)
			)
		)
		(duplicate_pad_numbers_are_jumpers no)
		(fp_line
			(start 0.299974 -0.150114)
			(end 0.299974 0.150114)
			(stroke
				(width 0.1)
				(type default)
			)
			(layer "F.Fab")
		)
		(fp_line
			(start -0.299974 -0.150114)
			(end 0.299974 -0.150114)
			(stroke
				(width 0.1)
				(type default)
			)
			(layer "F.Fab")
		)
		(fp_line
			(start 0.299974 0.150114)
			(end -0.299974 0.150114)
			(stroke
				(width 0.1)
				(type default)
			)
			(layer "F.Fab")
		)
		(fp_line
			(start -0.299974 0.150114)
			(end -0.299974 -0.150114)
			(stroke
				(width 0.1)
				(type default)
			)
			(layer "F.Fab")
		)
		(pad "1" smd rect
			(at -0.2667 0 90)
			(size 0.3048 0.381)
			(layers "F.Cu" "F.Mask" "F.Paste")
			(net "P5E_PEX2_STN5_TX_DP<89>")
		)
		(pad "2" smd rect
			(at 0.2667 0 90)
			(size 0.3048 0.381)
			(layers "F.Cu" "F.Mask" "F.Paste")
			(net "P5E_PEX2_STN5_TX_C_DP<89>")
		)
	)
	(footprint ""
		(layer "F.Cu")
		(at 361.188 -182.118)
		(property "Reference" "R4703"
			(at 0 0 0)
			(layer "F.SilkS")
			(hide yes)
			(effects
				(font
					(size 1.27 1.27)
				)
			)
		)
		(property "Value" ""
			(at 0 0 0)
			(layer "F.Fab")
			(effects
				(font
					(size 1.27 1.27)
				)
			)
		)
		(duplicate_pad_numbers_are_jumpers no)
		(fp_line
			(start -0.7874 -0.4064)
			(end 0.7874 -0.4064)
			(stroke
				(width 0.1524)
				(type default)
			)
			(layer "F.SilkS")
		)
		(fp_line
			(start -0.7874 0.4064)
			(end -0.7874 -0.4064)
			(stroke
				(width 0.1524)
				(type default)
			)
			(layer "F.SilkS")
		)
		(fp_line
			(start 0.7874 -0.4064)
			(end 0.7874 0.4064)
			(stroke
				(width 0.1524)
				(type default)
			)
			(layer "F.SilkS")
		)
		(fp_line
			(start 0.7874 0.4064)
			(end -0.7874 0.4064)
			(stroke
				(width 0.1524)
				(type default)
			)
			(layer "F.SilkS")
		)
		(fp_line
			(start -0.67945 -0.305054)
			(end -0.12065 -0.305054)
			(stroke
				(width 0.1)
				(type default)
			)
			(layer "F.Fab")
		)
		(fp_line
			(start -0.67945 0.3048)
			(end -0.67945 -0.305054)
			(stroke
				(width 0.1)
				(type default)
			)
			(layer "F.Fab")
		)
		(fp_line
			(start -0.12065 -0.305054)
			(end -0.12065 -0.2794)
			(stroke
				(width 0.1)
				(type default)
			)
			(layer "F.Fab")
		)
		(fp_line
			(start -0.12065 -0.2794)
			(end 0.12065 -0.2794)
			(stroke
				(width 0.1)
				(type default)
			)
			(layer "F.Fab")
		)
		(fp_line
			(start -0.12065 0.2794)
			(end -0.12065 0.3048)
			(stroke
				(width 0.1)
				(type default)
			)
			(layer "F.Fab")
		)
		(fp_line
			(start -0.12065 0.3048)
			(end -0.67945 0.3048)
			(stroke
				(width 0.1)
				(type default)
			)
			(layer "F.Fab")
		)
		(fp_line
			(start 0.120396 0.2794)
			(end -0.12065 0.2794)
			(stroke
				(width 0.1)
				(type default)
			)
			(layer "F.Fab")
		)
		(fp_line
			(start 0.120396 0.3048)
			(end 0.120396 0.2794)
			(stroke
				(width 0.1)
				(type default)
			)
			(layer "F.Fab")
		)
		(fp_line
			(start 0.12065 -0.3048)
			(end 0.67945 -0.3048)
			(stroke
				(width 0.1)
				(type default)
			)
			(layer "F.Fab")
		)
		(fp_line
			(start 0.12065 -0.2794)
			(end 0.12065 -0.3048)
			(stroke
				(width 0.1)
				(type default)
			)
			(layer "F.Fab")
		)
		(fp_line
			(start 0.67945 -0.3048)
			(end 0.67945 0.3048)
			(stroke
				(width 0.1)
				(type default)
			)
			(layer "F.Fab")
		)
		(fp_line
			(start 0.67945 0.3048)
			(end 0.120396 0.3048)
			(stroke
				(width 0.1)
				(type default)
			)
			(layer "F.Fab")
		)
		(pad "1" smd circle
			(at -0.40005 0)
			(size 0 0)
			(layers "F.Cu" "F.Mask" "F.Paste")
			(net "PEX1_PCA9555_1_INT_N")
		)
		(pad "2" smd circle
			(at 0.40005 0)
			(size 0 0)
			(layers "F.Cu" "F.Mask" "F.Paste")
			(net "P1V8_PEX")
		)
	)
	(footprint ""
		(layer "F.Cu")
		(at 46.125384 -42.849038 180)
		(property "Reference" "R524"
			(at 0 0 180)
			(layer "F.SilkS")
			(hide yes)
			(effects
				(font
					(size 1.27 1.27)
				)
			)
		)
		(property "Value" ""
			(at 0 0 180)
			(layer "F.Fab")
			(effects
				(font
					(size 1.27 1.27)
				)
			)
		)
		(duplicate_pad_numbers_are_jumpers no)
		(fp_line
			(start 0.7874 0.4064)
			(end -0.7874 0.4064)
			(stroke
				(width 0.1524)
				(type default)
			)
			(layer "F.SilkS")
		)
		(fp_line
			(start 0.7874 -0.4064)
			(end 0.7874 0.4064)
			(stroke
				(width 0.1524)
				(type default)
			)
			(layer "F.SilkS")
		)
		(fp_line
			(start -0.7874 0.4064)
			(end -0.7874 -0.4064)
			(stroke
				(width 0.1524)
				(type default)
			)
			(layer "F.SilkS")
		)
		(fp_line
			(start -0.7874 -0.4064)
			(end 0.7874 -0.4064)
			(stroke
				(width 0.1524)
				(type default)
			)
			(layer "F.SilkS")
		)
		(fp_line
			(start 0.67945 0.3048)
			(end 0.120396 0.3048)
			(stroke
				(width 0.1)
				(type default)
			)
			(layer "F.Fab")
		)
		(fp_line
			(start 0.67945 -0.3048)
			(end 0.67945 0.3048)
			(stroke
				(width 0.1)
				(type default)
			)
			(layer "F.Fab")
		)
		(fp_line
			(start 0.12065 -0.2794)
			(end 0.12065 -0.3048)
			(stroke
				(width 0.1)
				(type default)
			)
			(layer "F.Fab")
		)
		(fp_line
			(start 0.12065 -0.3048)
			(end 0.67945 -0.3048)
			(stroke
				(width 0.1)
				(type default)
			)
			(layer "F.Fab")
		)
		(fp_line
			(start 0.120396 0.3048)
			(end 0.120396 0.2794)
			(stroke
				(width 0.1)
				(type default)
			)
			(layer "F.Fab")
		)
		(fp_line
			(start 0.120396 0.2794)
			(end -0.12065 0.2794)
			(stroke
				(width 0.1)
				(type default)
			)
			(layer "F.Fab")
		)
		(fp_line
			(start -0.12065 0.3048)
			(end -0.67945 0.3048)
			(stroke
				(width 0.1)
				(type default)
			)
			(layer "F.Fab")
		)
		(fp_line
			(start -0.12065 0.2794)
			(end -0.12065 0.3048)
			(stroke
				(width 0.1)
				(type default)
			)
			(layer "F.Fab")
		)
		(fp_line
			(start -0.12065 -0.2794)
			(end 0.12065 -0.2794)
			(stroke
				(width 0.1)
				(type default)
			)
			(layer "F.Fab")
		)
		(fp_line
			(start -0.12065 -0.305054)
			(end -0.12065 -0.2794)
			(stroke
				(width 0.1)
				(type default)
			)
			(layer "F.Fab")
		)
		(fp_line
			(start -0.67945 0.3048)
			(end -0.67945 -0.305054)
			(stroke
				(width 0.1)
				(type default)
			)
			(layer "F.Fab")
		)
		(fp_line
			(start -0.67945 -0.305054)
			(end -0.12065 -0.305054)
			(stroke
				(width 0.1)
				(type default)
			)
			(layer "F.Fab")
		)
		(pad "1" smd circle
			(at -0.40005 0 180)
			(size 0 0)
			(layers "F.Cu" "F.Mask" "F.Paste")
			(net "P12V_SSD1_R")
		)
		(pad "2" smd circle
			(at 0.40005 0 180)
			(size 0 0)
			(layers "F.Cu" "F.Mask" "F.Paste")
			(net "P12V_SSD1_VIN_P")
		)
	)
)
